FILE_TYPE = MULTI_PHYS_TABLE;

PART 'ISL69260IRAZT'

{========================================================================================}
:VALUE                 | PART_TYPE | MATERIAL | PART_NUMBER    = STANDARD        | LIFECYCLE          | PART_NUMBER   | JEDEC_TYPE           | DESCRIPTION                                                             | MANUFTR | MANUF_PN              | RD_CMPLS_LVL | CMPLS_LVL | FROM_PJ     | CLASS | DIP_SMD | DATA                                            | EE_CHECK_LIST | FP_ECN                    | PSL | CREATOR | STATUS | MSD  | ESD_CDM | ESD_HBM | ESD_MM | PIN_LENGTH_SHORT_PIN | PIN_LENGTH_LONG_PIN | CREATEDAY  ;
{========================================================================================}
 'ISL69260IRAZ-T'      | 'SMLF'    | 'IC'     | 'AL069260000'(!) = ''              | ''                 | 'AL069260000' |'QFN40_TH_0-4_5X5XE'| 'IC CTRL(40P)ISL69260IRAZ-T(QFN)'                                       | 'RTT'   | 'ISL69260IRAZ-T'      | 'EP(V1)'     | ''        | 'S9S-KIMI'  | 'IC'  | ''      | 'RTT_ISL69260IRAZ-T.pdf'                        | ''            | 'ISL69260IRAZ-T.msg'      | ''  | ''      | ''     | 'NA' | 'na'    | 'na'    | 'na'   | '0 MILS'             | '0 MILS'            | '20200310'
 'ISL69260IRAZ-T'      | 'SMLF'    | 'EMPTY'  | 'AL069260000'(!) = ''              | ''                 | 'AL069260000' |'QFN40_TH_0-4_5X5XE'| 'IC CTRL(40P)ISL69260IRAZ-T(QFN)'                                       | 'RTT'   | 'ISL69260IRAZ-T'      | 'EP(V1)'     | ''        | 'S9S-KIMI'  | 'IC'  | ''      | 'RTT_ISL69260IRAZ-T.pdf'                        | ''            | 'ISL69260IRAZ-T.msg'      | ''  | ''      | ''     | 'NA' | 'na'    | 'na'    | 'na'   | '0 MILS'             | '0 MILS'            | '20200310'
 'ISL69260IRAZ-T'      | 'SMLF'    | 'IC'     | 'AR0S7PPF000'(!) = ''              | ''                 | 'AR0S7PPF000' |'QFN40_TH_0-4_5X5XE'| 'PROG IC(40P)ISL69260IRAZ-T(QFN) (checksum:70005688/0F93ACF5)'          | 'RTT'   | 'ISL69260IRAZ-T'      | 'EP(V1)'     | 'EP(V1)'  | 'S7P-FRANK' | 'IC'  | ''      | 'RTT_ISL69260IRAZ-T_70005688_0F93ACF5.pdf'      | ''            | 'ISL69260IRAZ-T.msg'      | ''  | ''      | ''     | ''   | ''      | ''      | ''     | '0 MILS'             | '0 MILS'            | '20210407'
 'ISL69260IRAZ-T'      | 'SMLF'    | 'EMPTY'  | 'AR0S7PPF000'(!) = ''              | ''                 | 'AR0S7PPF000' |'QFN40_TH_0-4_5X5XE'| 'PROG IC(40P)ISL69260IRAZ-T(QFN) (checksum:70005688/0F93ACF5)'          | 'RTT'   | 'ISL69260IRAZ-T'      | 'EP(V1)'     | 'EP(V1)'  | 'S7P-FRANK' | 'IC'  | ''      | 'RTT_ISL69260IRAZ-T_70005688_0F93ACF5.pdf'      | ''            | 'ISL69260IRAZ-T.msg'      | ''  | ''      | ''     | ''   | ''      | ''      | ''     | '0 MILS'             | '0 MILS'            | '20210407'
 'ISL69260IRAZ-TR5970' | 'SMLF'    | 'IC'     | 'AR0S8ZP2000'(!) = ''              | ''                 | 'AR0S8ZP2000' |'QFN40_TH_0-4_5X5XE'| 'PROGIC CTRL(40P)ISL69260(33B1AF06)SELASN'                              | 'RTT'   | 'ISL69260IRAZ-TR5970' | 'EP(V1)'     | 'EP(V1)'  | 'S8Z-FRANK' | 'IC'  | ''      | 'RTT_ISL69260IRAZ-TR5970_33B1AF06.pdf'          | ''            | 'ISL69260IRAZ-TR5970.msg' | ''  | ''      | ''     | 'NA' | 'NA'    | 'NA'    | 'NA'   | '0 MILS'             | '0 MILS'            | '20200611'
 'ISL69260IRAZ-TR5970' | 'SMLF'    | 'EMPTY'  | 'AR0S8ZP2000'(!) = ''              | ''                 | 'AR0S8ZP2000' |'QFN40_TH_0-4_5X5XE'| 'PROGIC CTRL(40P)ISL69260(33B1AF06)SELASN'                              | 'RTT'   | 'ISL69260IRAZ-TR5970' | 'EP(V1)'     | 'EP(V1)'  | 'S8Z-FRANK' | 'IC'  | ''      | 'RTT_ISL69260IRAZ-TR5970_33B1AF06.pdf'          | ''            | 'ISL69260IRAZ-TR5970.msg' | ''  | ''      | ''     | 'NA' | 'NA'    | 'NA'    | 'NA'   | '0 MILS'             | '0 MILS'            | '20200611'
 'ISL69260IRAZ-TR5970' | 'SMLF'    | 'IC'     | 'AR0S8ZP2001'(!) = ''              | ''                 | 'AR0S8ZP2001' |'QFN40_TH_0-4_5X5XE'| 'PROGIC CTRL(40P)ISL69260(37867851)SELASN'                              | 'RTT'   | 'ISL69260IRAZ-TR5970' | 'EP(V1)'     | 'EP(V1)'  | 'S8Z-FRANK' | 'IC'  | ''      | 'RTT_ISL69260IRAZ-TR5970_37867851.pdf'          | ''            | 'ISL69260IRAZ-TR5970.msg' | ''  | ''      | ''     | 'NA' | 'NA'    | 'NA'    | 'NA'   | '0 MILS'             | '0 MILS'            | '20200612'
 'ISL69260IRAZ-TR5970' | 'SMLF'    | 'EMPTY'  | 'AR0S8ZP2001'(!) = ''              | ''                 | 'AR0S8ZP2001' |'QFN40_TH_0-4_5X5XE'| 'PROGIC CTRL(40P)ISL69260(37867851)SELASN'                              | 'RTT'   | 'ISL69260IRAZ-TR5970' | 'EP(V1)'     | 'EP(V1)'  | 'S8Z-FRANK' | 'IC'  | ''      | 'RTT_ISL69260IRAZ-TR5970_37867851.pdf'          | ''            | 'ISL69260IRAZ-TR5970.msg' | ''  | ''      | ''     | 'NA' | 'NA'    | 'NA'    | 'NA'   | '0 MILS'             | '0 MILS'            | '20200612'
 'ISL69260IRAZ-TR5970' | 'SMLF'    | 'IC'     | 'AR0S8ZP2007'(!) = ''              | ''                 | 'AR0S8ZP2007' |'QFN40_TH_0-4_5X5XE'| 'PROGIC CTRL(40P)ISL69260IRAZ-TR59 SELASN (checksum:919829B1/2FFB4B79)' | 'RTT'   | 'ISL69260IRAZ-TR5970' | 'EP(V1)'     | 'EP(V1)'  | 'S8Z-FRANK' | 'IC'  | ''      | 'RTT_ISL69260IRAZ-TR5970_919829B1_2FFB4B79.pdf' | ''            | 'ISL69260IRAZ-TR5970.msg' | ''  | ''      | ''     | 'NA' | 'NA'    | 'NA'    | 'NA'   | '0 MILS'             | '0 MILS'            | '20200821'
 'ISL69260IRAZ-TR5970' | 'SMLF'    | 'EMPTY'  | 'AR0S8ZP2007'(!) = ''              | ''                 | 'AR0S8ZP2007' |'QFN40_TH_0-4_5X5XE'| 'PROGIC CTRL(40P)ISL69260IRAZ-TR59 SELASN (checksum:919829B1/2FFB4B79)' | 'RTT'   | 'ISL69260IRAZ-TR5970' | 'EP(V1)'     | 'EP(V1)'  | 'S8Z-FRANK' | 'IC'  | ''      | 'RTT_ISL69260IRAZ-TR5970_919829B1_2FFB4B79.pdf' | ''            | 'ISL69260IRAZ-TR5970.msg' | ''  | ''      | ''     | 'NA' | 'NA'    | 'NA'    | 'NA'   | '0 MILS'             | '0 MILS'            | '20200821'
 'ISL69260IRAZ-TR5970' | 'SMLF'    | 'IC'     | 'AR0S8ZP2011'(!) = ''              | ''                 | 'AR0S8ZP2011' |'QFN40_TH_0-4_5X5XE'| 'PROG IC(40P)ISL69260IRAZ-TR5970 SELASN (checksum:C99E36D6/B20782E7)'   | 'RTT'   | 'ISL69260IRAZ-TR5970' | 'EP(V1)'     | 'EP(V1)'  | 'S8Z-BRIAN' | 'IC'  | ''      | 'RTT_ISL69260IRAZ-TR5970_C99E36D6_B20782E7.pdf' | ''            | 'ISL69260IRAZ-TR5970.msg' | ''  | ''      | ''     | 'NA' | 'NA'    | 'NA'    | 'NA'   | '0 MILS'             | '0 MILS'            | '20201014'
 'ISL69260IRAZ-TR5970' | 'SMLF'    | 'EMPTY'  | 'AR0S8ZP2011'(!) = ''              | ''                 | 'AR0S8ZP2011' |'QFN40_TH_0-4_5X5XE'| 'PROG IC(40P)ISL69260IRAZ-TR5970 SELASN (checksum:C99E36D6/B20782E7)'   | 'RTT'   | 'ISL69260IRAZ-TR5970' | 'EP(V1)'     | 'EP(V1)'  | 'S8Z-BRIAN' | 'IC'  | ''      | 'RTT_ISL69260IRAZ-TR5970_C99E36D6_B20782E7.pdf' | ''            | 'ISL69260IRAZ-TR5970.msg' | ''  | ''      | ''     | 'NA' | 'NA'    | 'NA'    | 'NA'   | '0 MILS'             | '0 MILS'            | '20201014'
 'ISL69260IRAZ-TR5970' | 'SMLF'    | 'IC'     | 'AR0S8ZP2012'(!) = ''              | ''                 | 'AR0S8ZP2012' |'QFN40_TH_0-4_5X5XE'| 'PROG IC(40P)ISL69260IRAZ-TR5970 SELASN (checksum:3D8CF0B0/2597ADDE)'   | 'RTT'   | 'ISL69260IRAZ-TR5970' | 'EP(V1)'     | 'EP(V1)'  | 'S8Z-BRIAN' | 'IC'  | ''      | 'RTT_ISL69260IRAZ-TR5970_3D8CF0B0_2597ADDE.pdf' | ''            | 'ISL69260IRAZ-TR5970.msg' | ''  | ''      | ''     | 'NA' | 'N/A'   | 'N/A'   | 'N/A'  | '0 MILS'             | '0 MILS'            | '20201211'
 'ISL69260IRAZ-TR5970' | 'SMLF'    | 'EMPTY'  | 'AR0S8ZP2012'(!) = ''              | ''                 | 'AR0S8ZP2012' |'QFN40_TH_0-4_5X5XE'| 'PROG IC(40P)ISL69260IRAZ-TR5970 SELASN (checksum:3D8CF0B0/2597ADDE)'   | 'RTT'   | 'ISL69260IRAZ-TR5970' | 'EP(V1)'     | 'EP(V1)'  | 'S8Z-BRIAN' | 'IC'  | ''      | 'RTT_ISL69260IRAZ-TR5970_3D8CF0B0_2597ADDE.pdf' | ''            | 'ISL69260IRAZ-TR5970.msg' | ''  | ''      | ''     | 'NA' | 'N/A'   | 'N/A'   | 'N/A'  | '0 MILS'             | '0 MILS'            | '20201211'
 'ISL69260IRAZ-TR5970' | 'SMLF'    | 'IC'     | 'AR0S8ZP2020'(!) = ''              | ''                 | 'AR0S8ZP2020' |'QFN40_TH_0-4_5X5XE'| 'PROG IC(41P)ISL69260IRAZ-TR5970 SELASN (checksum:DDBB8638/F00DB4C3)'   | 'RTT'   | 'ISL69260IRAZ-TR5970' | 'EP(V1)'     | 'EP(V1)'  | 'S8Z-BRIAN' | 'IC'  | ''      | 'RTT_ISL69260IRAZ-TR5970_DDBB8638_F00DB4C3.pdf' | ''            | 'ISL69260IRAZ-TR5970.msg' | ''  | ''      | ''     | ''   | ''      | ''      | ''     | '0 MILS'             | '0 MILS'            | '20210429'
 'ISL69260IRAZ-TR5970' | 'SMLF'    | 'EMPTY'  | 'AR0S8ZP2020'(!) = ''              | ''                 | 'AR0S8ZP2020' |'QFN40_TH_0-4_5X5XE'| 'PROG IC(41P)ISL69260IRAZ-TR5970 SELASN (checksum:DDBB8638/F00DB4C3)'   | 'RTT'   | 'ISL69260IRAZ-TR5970' | 'EP(V1)'     | 'EP(V1)'  | 'S8Z-BRIAN' | 'IC'  | ''      | 'RTT_ISL69260IRAZ-TR5970_DDBB8638_F00DB4C3.pdf' | ''            | 'ISL69260IRAZ-TR5970.msg' | ''  | ''      | ''     | ''   | ''      | ''      | ''     | '0 MILS'             | '0 MILS'            | '20210429'
 'ISL69260IRAZ-T'      | 'SMLF'    | 'IC'     | 'ARF0TGP4004'(!) = ''              | ''                 | 'ARF0TGP4004' |'QFN40_TH_0-4_5X5XE'| 'PROG IC(41P)ISL69260IRAZ-T(QFN)85E1D364'                               | 'RTT'   | 'ISL69260IRAZ-T'      | 'EP(V1)'     | 'EP(V1)'  | 'F0TG-CART' | 'IC'  | ''      | 'RTT_ISL69260IRAZ-T_85E1D364.pdf'               | ''            | 'ISL69260IRAZ-T.msg'      | ''  | ''      | ''     | ''   | ''      | ''      | ''     | '0 MILS'             | '0 MILS'            | '20210407'
 'ISL69260IRAZ-T'      | 'SMLF'    | 'EMPTY'  | 'ARF0TGP4004'(!) = ''              | ''                 | 'ARF0TGP4004' |'QFN40_TH_0-4_5X5XE'| 'PROG IC(41P)ISL69260IRAZ-T(QFN)85E1D364'                               | 'RTT'   | 'ISL69260IRAZ-T'      | 'EP(V1)'     | 'EP(V1)'  | 'F0TG-CART' | 'IC'  | ''      | 'RTT_ISL69260IRAZ-T_85E1D364.pdf'               | ''            | 'ISL69260IRAZ-T.msg'      | ''  | ''      | ''     | ''   | ''      | ''      | ''     | '0 MILS'             | '0 MILS'            | '20210407'
 'ISL69260IRAZ-T'      | 'SMLF'    | 'IC'     | 'ARF0TGP4009'(!) = ''               | ''               | 'ARF0TGP4009' |'QFN40_TH_0-4_5X5XE'| 'PROG IC (41P) ISL69260IRAZ-T (C1C901A0)'                               | 'RTT'   | 'ISL69260IRAZ-T'      | 'EP(V1)'     | 'EP(V1)'  | 'F0TG-CART' | 'IC'  | ''      | 'RTT_ISL69260IRAZ-T_C1C901A0.pdf'               | ''            | 'ISL69260IRAZ-T.msg'      | ''  | ''      | ''     | ''   | ''      | ''      | ''     | '0 MILS'             | '0 MILS'            | '20230327'
 'ISL69260IRAZ-T'      | 'SMLF'    | 'EMPTY'  | 'ARF0TGP4009'(!) = ''               | ''               | 'ARF0TGP4009' |'QFN40_TH_0-4_5X5XE'| 'PROG IC (41P) ISL69260IRAZ-T (C1C901A0)'                               | 'RTT'   | 'ISL69260IRAZ-T'      | 'EP(V1)'     | 'EP(V1)'  | 'F0TG-CART' | 'IC'  | ''      | 'RTT_ISL69260IRAZ-T_C1C901A0.pdf'               | ''            | 'ISL69260IRAZ-T.msg'      | ''  | ''      | ''     | ''   | ''      | ''      | ''     | '0 MILS'             | '0 MILS'            | '20230327'

END_PART

END.

